(kicad_pcb
	(version 20241229)
	(generator "pcbnew")
	(generator_version "9.0")
	(general
		(thickness 1.711)
		(legacy_teardrops no)
	)
	(paper "A4")
	(title_block
		(title "Antmicro Baseboard for Jetson AGX Thor")
		(date "2026-02-18")
		(rev "1.1.0")
		(company "Antmicro Ltd")
		(comment 1 "www.antmicro.com")
		(comment 9 "footprints 920-924 of 1170")
	)
	(layers
		(0 "F.Cu" signal)
		(4 "In1.Cu" signal)
		(6 "In2.Cu" signal)
		(8 "In3.Cu" signal)
		(10 "In4.Cu" jumper)
		(12 "In5.Cu" signal)
		(14 "In6.Cu" signal)
		(16 "In7.Cu" signal)
		(18 "In8.Cu" signal)
		(2 "B.Cu" signal)
		(9 "F.Adhes" user "F.Adhesive")
		(11 "B.Adhes" user "B.Adhesive")
		(13 "F.Paste" user)
		(15 "B.Paste" user)
		(5 "F.SilkS" user "F.Silkscreen")
		(7 "B.SilkS" user "B.Silkscreen")
		(1 "F.Mask" user)
		(3 "B.Mask" user)
		(17 "Dwgs.User" user "User.Drawings")
		(19 "Cmts.User" user "User.Comments")
		(21 "Eco1.User" user "User.Eco1")
		(23 "Eco2.User" user "User.Eco2")
		(25 "Edge.Cuts" user)
		(27 "Margin" user)
		(31 "F.CrtYd" user "F.Courtyard")
		(29 "B.CrtYd" user "B.Courtyard")
		(35 "F.Fab" user)
		(33 "B.Fab" user)
	)
	(footprint "antmicro-footprints:R_0402_1005Metric"
		(layer "B.Cu")
		(at 220.66 113.03)
		(descr "Resistor SMD 0402")
		(tags "resistor SMD 0402")
		(property "Reference" "R328"
			(at -1.06 1.77 0)
			(layer "B.SilkS")
			(effects
				(font
					(size 0.7 0.7)
					(thickness 0.15)
				)
				(justify right top mirror)
			)
		)
		(property "Value" "R_10k_0402"
			(at -1.011843 -1.772047 0)
			(layer "B.Fab")
			(effects
				(font
					(size 0.7 0.7)
					(thickness 0.15)
				)
				(justify right top mirror)
			)
		)
		(property "Datasheet" "https://www.bourns.com/docs/product-datasheets/cr.pdf"
			(at 0 0 0)
			(layer "B.Fab")
			(hide yes)
			(effects
				(font
					(size 1.27 1.27)
					(thickness 0.15)
				)
				(justify mirror)
			)
		)
		(property "Description" "SMD Chip Resistor, 10 kohm, ± 1%, 62.5 mW, 0402 [1005 Metric], Thick Film, General Purpose"
			(at 0 0 0)
			(layer "B.Fab")
			(hide yes)
			(effects
				(font
					(size 1.27 1.27)
					(thickness 0.15)
				)
				(justify mirror)
			)
		)
		(property "MPN" "CR0402-FX-1002GLF"
			(at 0 0 180)
			(unlocked yes)
			(layer "B.Fab")
			(hide yes)
			(effects
				(font
					(size 1 1)
					(thickness 0.15)
				)
				(justify mirror)
			)
		)
		(property "Manufacturer" "Bourns"
			(at 0 0 180)
			(unlocked yes)
			(layer "B.Fab")
			(hide yes)
			(effects
				(font
					(size 1 1)
					(thickness 0.15)
				)
				(justify mirror)
			)
		)
		(property "License" "Apache-2.0"
			(at 0 0 180)
			(unlocked yes)
			(layer "B.Fab")
			(hide yes)
			(effects
				(font
					(size 1 1)
					(thickness 0.15)
				)
				(justify mirror)
			)
		)
		(property "Author" "Antmicro"
			(at 0 0 180)
			(unlocked yes)
			(layer "B.Fab")
			(hide yes)
			(effects
				(font
					(size 1 1)
					(thickness 0.15)
				)
				(justify mirror)
			)
		)
		(property "Val" "10k"
			(at 0 0 180)
			(unlocked yes)
			(layer "B.Fab")
			(hide yes)
			(effects
				(font
					(size 1 1)
					(thickness 0.15)
				)
				(justify mirror)
			)
		)
		(property "Tolerance" "1%"
			(at 0 0 180)
			(unlocked yes)
			(layer "B.Fab")
			(hide yes)
			(effects
				(font
					(size 1 1)
					(thickness 0.15)
				)
				(justify mirror)
			)
		)
		(sheetname "/USB Hub/")
		(sheetfile "usb_hub.kicad_sch")
		(attr smd)
		(fp_rect
			(start -0.925 0.47)
			(end 0.925 -0.47)
			(stroke
				(width 0.05)
				(type default)
			)
			(fill no)
			(layer "B.CrtYd")
		)
		(fp_rect
			(start -0.5 0.25)
			(end 0.5 -0.25)
			(stroke
				(width 0.15)
				(type solid)
			)
			(fill no)
			(layer "B.Fab")
		)
		(fp_text user "${REFERENCE}"
			(at -0.95 -3.168 0)
			(layer "B.Fab")
			(effects
				(font
					(size 0.7 0.7)
					(thickness 0.15)
				)
				(justify right top mirror)
			)
		)
		(fp_text user "Author: Antmicro"
			(at -0.95 -4.169 0)
			(layer "B.Fab")
			(effects
				(font
					(size 0.7 0.7)
					(thickness 0.15)
				)
				(justify right top mirror)
			)
		)
		(fp_text user "License: Apache-2.0"
			(at -0.95 -5.169 0)
			(layer "B.Fab")
			(effects
				(font
					(size 0.7 0.7)
					(thickness 0.15)
				)
				(justify right top mirror)
			)
		)
		(pad "1" smd roundrect
			(at -0.48 0)
			(size 0.59 0.64)
			(layers "B.Cu" "B.Mask" "B.Paste")
			(roundrect_rratio 0.25)
			(net 1099 "/USB Hub/DP2_VCONN1")
			(pintype "passive")
		)
		(pad "2" smd roundrect
			(at 0.48 0)
			(size 0.59 0.64)
			(layers "B.Cu" "B.Mask" "B.Paste")
			(roundrect_rratio 0.25)
			(net 1 "GND")
			(pintype "passive")
		)
	)
	(footprint "antmicro-footprints:C_0402_1005Metric"
		(layer "B.Cu")
		(at 109.92 70.63)
		(descr "Capacitor SMD 0402")
		(tags "capacitor SMD 0402")
		(property "Reference" "C12"
			(at -1.02 0.67 0)
			(layer "B.SilkS")
			(effects
				(font
					(size 0.7 0.7)
					(thickness 0.15)
				)
				(justify right top mirror)
			)
		)
		(property "Value" "C_10u_0402"
			(at -1.022927 -2.155213 0)
			(layer "B.Fab")
			(effects
				(font
					(size 0.7 0.7)
					(thickness 0.15)
				)
				(justify right top mirror)
			)
		)
		(property "Datasheet" "https://www.yageo.com/en/Chart/Download/pdf/CC0402MRX5R5BB106"
			(at 0 0 0)
			(layer "B.Fab")
			(hide yes)
			(effects
				(font
					(size 1.27 1.27)
					(thickness 0.15)
				)
				(justify mirror)
			)
		)
		(property "Description" "SMD Multilayer Ceramic Capacitor, 10 µF, 6.3 V, 0402 [1005 Metric], ± 20%, X5R, CC Series"
			(at 0 0 0)
			(layer "B.Fab")
			(hide yes)
			(effects
				(font
					(size 1.27 1.27)
					(thickness 0.15)
				)
				(justify mirror)
			)
		)
		(property "MPN" "CC0402MRX5R5BB106"
			(at 0 0 0)
			(unlocked yes)
			(layer "B.Fab")
			(hide yes)
			(effects
				(font
					(size 1 1)
					(thickness 0.15)
				)
				(justify mirror)
			)
		)
		(property "Manufacturer" "YAGEO"
			(at 0 0 0)
			(unlocked yes)
			(layer "B.Fab")
			(hide yes)
			(effects
				(font
					(size 1 1)
					(thickness 0.15)
				)
				(justify mirror)
			)
		)
		(property "License" "Apache-2.0"
			(at 0 0 0)
			(unlocked yes)
			(layer "B.Fab")
			(hide yes)
			(effects
				(font
					(size 1 1)
					(thickness 0.15)
				)
				(justify mirror)
			)
		)
		(property "Author" "Antmicro"
			(at 0 0 0)
			(unlocked yes)
			(layer "B.Fab")
			(hide yes)
			(effects
				(font
					(size 1 1)
					(thickness 0.15)
				)
				(justify mirror)
			)
		)
		(property "Val" "10u"
			(at 0 0 0)
			(unlocked yes)
			(layer "B.Fab")
			(hide yes)
			(effects
				(font
					(size 1 1)
					(thickness 0.15)
				)
				(justify mirror)
			)
		)
		(property "Voltage" ""
			(at 0 0 0)
			(unlocked yes)
			(layer "B.Fab")
			(hide yes)
			(effects
				(font
					(size 1 1)
					(thickness 0.15)
				)
				(justify mirror)
			)
		)
		(property "Dielectric" "template_dielectric"
			(at 0 0 0)
			(unlocked yes)
			(layer "B.Fab")
			(hide yes)
			(effects
				(font
					(size 1 1)
					(thickness 0.15)
				)
				(justify mirror)
			)
		)
		(sheetname "/SoM_Power/")
		(sheetfile "som_power.kicad_sch")
		(attr smd)
		(fp_rect
			(start -0.925 0.47)
			(end 0.925 -0.47)
			(stroke
				(width 0.05)
				(type default)
			)
			(fill no)
			(layer "B.CrtYd")
		)
		(fp_line
			(start -0.494 -0.248)
			(end -0.494 0.25)
			(stroke
				(width 0.15)
				(type solid)
			)
			(layer "B.Fab")
		)
		(fp_line
			(start -0.494 0.25)
			(end 0.504 0.25)
			(stroke
				(width 0.15)
				(type solid)
			)
			(layer "B.Fab")
		)
		(fp_line
			(start 0.504 -0.248)
			(end -0.494 -0.248)
			(stroke
				(width 0.15)
				(type solid)
			)
			(layer "B.Fab")
		)
		(fp_line
			(start 0.504 0.25)
			(end 0.504 -0.248)
			(stroke
				(width 0.15)
				(type solid)
			)
			(layer "B.Fab")
		)
		(fp_text user "${REFERENCE}"
			(at -0.939 -4.599 0)
			(layer "B.Fab")
			(effects
				(font
					(size 0.7 0.7)
					(thickness 0.15)
				)
				(justify right top mirror)
			)
		)
		(fp_text user "Author: Antmicro"
			(at -0.939 -3.399 0)
			(layer "B.Fab")
			(effects
				(font
					(size 0.7 0.7)
					(thickness 0.15)
				)
				(justify right top mirror)
			)
		)
		(fp_text user "License: Apache-2.0"
			(at -0.939 -5.799 0)
			(layer "B.Fab")
			(effects
				(font
					(size 0.7 0.7)
					(thickness 0.15)
				)
				(justify right top mirror)
			)
		)
		(pad "1" smd roundrect
			(at -0.48 0)
			(size 0.59 0.64)
			(layers "B.Cu" "B.Mask" "B.Paste")
			(roundrect_rratio 0.25)
			(net 1 "GND")
			(pintype "passive")
		)
		(pad "2" smd roundrect
			(at 0.48 0)
			(size 0.59 0.64)
			(layers "B.Cu" "B.Mask" "B.Paste")
			(roundrect_rratio 0.25)
			(net 213 "+5V_SOM")
			(pintype "passive")
		)
	)
	(footprint "antmicro-footprints:TP_SMD_0.75mm"
		(layer "B.Cu")
		(at 122.86 55.29 -90)
		(property "Reference" "TP79"
			(at 0.5 0.6 0)
			(layer "B.SilkS")
			(effects
				(font
					(size 0.7 0.7)
					(thickness 0.15)
				)
				(justify left bottom mirror)
			)
		)
		(property "Value" "TP_0.75mm_SMD"
			(at 0 -1.2 90)
			(layer "B.Fab")
			(effects
				(font
					(size 0.7 0.7)
					(thickness 0.15)
				)
				(justify left bottom mirror)
			)
		)
		(property "Description" "SMT test point"
			(at 0 0 90)
			(layer "B.Fab")
			(hide yes)
			(effects
				(font
					(size 1.27 1.27)
					(thickness 0.15)
				)
				(justify mirror)
			)
		)
		(property "MPN" ""
			(at 0 0 90)
			(unlocked yes)
			(layer "B.Fab")
			(hide yes)
			(effects
				(font
					(size 1 1)
					(thickness 0.15)
				)
				(justify mirror)
			)
		)
		(property "Manufacturer" ""
			(at 0 0 90)
			(unlocked yes)
			(layer "B.Fab")
			(hide yes)
			(effects
				(font
					(size 1 1)
					(thickness 0.15)
				)
				(justify mirror)
			)
		)
		(property "Author" "Antmicro"
			(at 0 0 90)
			(unlocked yes)
			(layer "B.Fab")
			(hide yes)
			(effects
				(font
					(size 1 1)
					(thickness 0.15)
				)
				(justify mirror)
			)
		)
		(property "License" "Apache-2.0"
			(at 0 0 90)
			(unlocked yes)
			(layer "B.Fab")
			(hide yes)
			(effects
				(font
					(size 1 1)
					(thickness 0.15)
				)
				(justify mirror)
			)
		)
		(sheetname "/SoM_Power/")
		(sheetfile "som_power.kicad_sch")
		(attr exclude_from_pos_files exclude_from_bom)
		(fp_circle
			(center 0 0)
			(end 0.475 0)
			(stroke
				(width 0.05)
				(type default)
			)
			(fill no)
			(layer "B.CrtYd")
		)
		(fp_text user "License: Apache-2.0"
			(at -0.4 -5.101 90)
			(layer "B.Fab")
			(effects
				(font
					(size 0.7 0.7)
					(thickness 0.15)
				)
				(justify left bottom mirror)
			)
		)
		(fp_text user "${REFERENCE}"
			(at -0.4 -2.7 90)
			(layer "B.Fab")
			(effects
				(font
					(size 0.7 0.7)
					(thickness 0.15)
				)
				(justify left bottom mirror)
			)
		)
		(fp_text user "Author: Antmicro"
			(at -0.4 -3.901 90)
			(layer "B.Fab")
			(effects
				(font
					(size 0.7 0.7)
					(thickness 0.15)
				)
				(justify left bottom mirror)
			)
		)
		(pad "1" smd circle
			(at 0 0 270)
			(size 0.75 0.75)
			(layers "B.Cu" "B.Mask")
			(net 1287 "/SoM_Power/MODULE_POWER_ON")
			(pinfunction "1")
			(pintype "passive")
		)
	)
	(footprint "antmicro-footprints:C_0805_2012Metric"
		(layer "B.Cu")
		(at 229.4 121.6 90)
		(descr "Capacitor SMD 0805")
		(tags "capacitor SMD 0805")
		(property "Reference" "C78"
			(at -1 -1.9 90)
			(layer "B.SilkS")
			(effects
				(font
					(size 0.7 0.7)
					(thickness 0.15)
				)
				(justify right top mirror)
			)
		)
		(property "Value" "C_22u_25V_0805"
			(at -2.055717 -1.963153 90)
			(layer "B.Fab")
			(effects
				(font
					(size 0.7 0.7)
					(thickness 0.15)
				)
				(justify right top mirror)
			)
		)
		(property "Datasheet" "https://product.samsungsem.com/mlcc/CL21A226MAYNNN.do"
			(at 0 0 90)
			(layer "B.Fab")
			(hide yes)
			(effects
				(font
					(size 1.27 1.27)
					(thickness 0.15)
				)
				(justify mirror)
			)
		)
		(property "Description" "SMT Multilayer Ceramic Capacitor, 22uF, +/-20%, 25V, X5R, 0805 [2012 Metric]"
			(at 0 0 90)
			(layer "B.Fab")
			(hide yes)
			(effects
				(font
					(size 1.27 1.27)
					(thickness 0.15)
				)
				(justify mirror)
			)
		)
		(property "Manufacturer" "Samsung Electro-Mechanics"
			(at 0 0 90)
			(unlocked yes)
			(layer "B.Fab")
			(hide yes)
			(effects
				(font
					(size 1 1)
					(thickness 0.15)
				)
				(justify mirror)
			)
		)
		(property "MPN" "CL21A226MAYNNNE"
			(at 0 0 90)
			(unlocked yes)
			(layer "B.Fab")
			(hide yes)
			(effects
				(font
					(size 1 1)
					(thickness 0.15)
				)
				(justify mirror)
			)
		)
		(property "Val" "22u"
			(at 0 0 90)
			(unlocked yes)
			(layer "B.Fab")
			(hide yes)
			(effects
				(font
					(size 1 1)
					(thickness 0.15)
				)
				(justify mirror)
			)
		)
		(property "License" "Apache-2.0"
			(at 0 0 90)
			(unlocked yes)
			(layer "B.Fab")
			(hide yes)
			(effects
				(font
					(size 1 1)
					(thickness 0.15)
				)
				(justify mirror)
			)
		)
		(property "Author" "Antmicro"
			(at 0 0 90)
			(unlocked yes)
			(layer "B.Fab")
			(hide yes)
			(effects
				(font
					(size 1 1)
					(thickness 0.15)
				)
				(justify mirror)
			)
		)
		(property "Voltage" "25V"
			(at 0 0 90)
			(unlocked yes)
			(layer "B.Fab")
			(hide yes)
			(effects
				(font
					(size 1 1)
					(thickness 0.15)
				)
				(justify mirror)
			)
		)
		(property "Dielectric" "X5R"
			(at 0 0 90)
			(unlocked yes)
			(layer "B.Fab")
			(hide yes)
			(effects
				(font
					(size 1 1)
					(thickness 0.15)
				)
				(justify mirror)
			)
		)
		(property "Public" "False"
			(at 0 0 90)
			(unlocked yes)
			(layer "B.Fab")
			(hide yes)
			(effects
				(font
					(size 1 1)
					(thickness 0.15)
				)
				(justify mirror)
			)
		)
		(sheetname "/USB Hub/")
		(sheetfile "usb_hub.kicad_sch")
		(attr smd)
		(fp_line
			(start -0.3 -0.7)
			(end 0.3 -0.7)
			(stroke
				(width 0.15)
				(type solid)
			)
			(layer "B.SilkS")
		)
		(fp_line
			(start -0.3 0.7)
			(end 0.3 0.7)
			(stroke
				(width 0.15)
				(type solid)
			)
			(layer "B.SilkS")
		)
		(fp_poly
			(pts
				(xy 1.95 0.9) (xy -1.95 0.9) (xy -1.95 -0.9) (xy 1.95 -0.9)
			)
			(stroke
				(width 0.05)
				(type default)
			)
			(fill no)
			(layer "B.CrtYd")
		)
		(fp_poly
			(pts
				(xy -0.95 0.675001) (xy 0.95 0.675001) (xy 0.95 -0.675001) (xy -0.95 -0.675001)
			)
			(stroke
				(width 0.15)
				(type solid)
			)
			(fill no)
			(layer "B.Fab")
		)
		(fp_text user "License: Apache-2.0"
			(at -1.9 -4.947 90)
			(layer "B.Fab")
			(effects
				(font
					(size 0.7 0.7)
					(thickness 0.15)
				)
				(justify right top mirror)
			)
		)
		(fp_text user "Author: Antmicro"
			(at -1.9 -5.947 90)
			(layer "B.Fab")
			(effects
				(font
					(size 0.7 0.7)
					(thickness 0.15)
				)
				(justify right top mirror)
			)
		)
		(fp_text user "${REFERENCE}"
			(at -1.899999 -3.947 90)
			(layer "B.Fab")
			(effects
				(font
					(size 0.7 0.7)
					(thickness 0.15)
				)
				(justify right top mirror)
			)
		)
		(pad "1" smd roundrect
			(at -1.099999 0 90)
			(size 1.2 1.3)
			(layers "B.Cu" "B.Mask" "B.Paste")
			(roundrect_rratio 0.25)
			(net 71 "/USB Hub/USBC3_VBUS")
			(pintype "passive")
		)
		(pad "2" smd roundrect
			(at 1.099999 0 90)
			(size 1.2 1.3)
			(layers "B.Cu" "B.Mask" "B.Paste")
			(roundrect_rratio 0.25)
			(net 1 "GND")
			(pintype "passive")
		)
	)
	(footprint "antmicro-footprints:C_0603_1608Metric_EIA"
		(layer "B.Cu")
		(at 123.47 69.52 180)
		(descr "Capacitor SMD 0603, IPC-7351 Density Level A")
		(tags "Capacitor 0603")
		(property "Reference" "C20"
			(at -1.13 0.82 0)
			(layer "B.SilkS")
			(effects
				(font
					(size 0.7 0.7)
					(thickness 0.15)
				)
				(justify left bottom mirror)
			)
		)
		(property "Value" "C_22u_16V_0603"
			(at -1.42757 -1.770288 0)
			(layer "B.Fab")
			(effects
				(font
					(size 0.7 0.7)
					(thickness 0.15)
				)
				(justify left bottom mirror)
			)
		)
		(property "Datasheet" "https://product.samsungsem.com/mlcc/CL10A226MO7JZN.do"
			(at 0 0 0)
			(layer "B.Fab")
			(hide yes)
			(effects
				(font
					(size 1.27 1.27)
					(thickness 0.15)
				)
				(justify mirror)
			)
		)
		(property "Description" "SMD Multilayer Ceramic Capacitor"
			(at 0 0 0)
			(layer "B.Fab")
			(hide yes)
			(effects
				(font
					(size 1.27 1.27)
					(thickness 0.15)
				)
				(justify mirror)
			)
		)
		(property "MPN" "CL10A226MO7JZNC"
			(at 0 0 0)
			(unlocked yes)
			(layer "B.Fab")
			(hide yes)
			(effects
				(font
					(size 1 1)
					(thickness 0.15)
				)
				(justify mirror)
			)
		)
		(property "Manufacturer" "Samsung Electro-Mechanics"
			(at 0 0 0)
			(unlocked yes)
			(layer "B.Fab")
			(hide yes)
			(effects
				(font
					(size 1 1)
					(thickness 0.15)
				)
				(justify mirror)
			)
		)
		(property "License" "Apache-2.0"
			(at 0 0 0)
			(unlocked yes)
			(layer "B.Fab")
			(hide yes)
			(effects
				(font
					(size 1 1)
					(thickness 0.15)
				)
				(justify mirror)
			)
		)
		(property "Author" "Antmicro"
			(at 0 0 0)
			(unlocked yes)
			(layer "B.Fab")
			(hide yes)
			(effects
				(font
					(size 1 1)
					(thickness 0.15)
				)
				(justify mirror)
			)
		)
		(property "Val" "22u"
			(at 0 0 0)
			(unlocked yes)
			(layer "B.Fab")
			(hide yes)
			(effects
				(font
					(size 1 1)
					(thickness 0.15)
				)
				(justify mirror)
			)
		)
		(property "Voltage" "16V"
			(at 0 0 0)
			(unlocked yes)
			(layer "B.Fab")
			(hide yes)
			(effects
				(font
					(size 1 1)
					(thickness 0.15)
				)
				(justify mirror)
			)
		)
		(property "Dielectric" "X7R"
			(at 0 0 0)
			(unlocked yes)
			(layer "B.Fab")
			(hide yes)
			(effects
				(font
					(size 1 1)
					(thickness 0.15)
				)
				(justify mirror)
			)
		)
		(property "Public" "False"
			(at 0 0 0)
			(unlocked yes)
			(layer "B.Fab")
			(hide yes)
			(effects
				(font
					(size 1 1)
					(thickness 0.15)
				)
				(justify mirror)
			)
		)
		(sheetname "/SoM_Power/")
		(sheetfile "som_power.kicad_sch")
		(attr smd)
		(fp_line
			(start -0.15 0.55)
			(end 0.15 0.55)
			(stroke
				(width 0.15)
				(type solid)
			)
			(layer "B.SilkS")
		)
		(fp_line
			(start -0.15 -0.55)
			(end 0.15 -0.55)
			(stroke
				(width 0.15)
				(type solid)
			)
			(layer "B.SilkS")
		)
		(fp_rect
			(start -1.25 0.65)
			(end 1.25 -0.65)
			(stroke
				(width 0.05)
				(type solid)
			)
			(fill no)
			(layer "B.CrtYd")
		)
		(fp_rect
			(start -0.8 0.45)
			(end 0.8 -0.45)
			(stroke
				(width 0.15)
				(type solid)
			)
			(fill no)
			(layer "B.Fab")
		)
		(fp_text user "License: Apache-2.0"
			(at -1.682 -5.895 0)
			(layer "B.Fab")
			(effects
				(font
					(size 0.7 0.7)
					(thickness 0.15)
				)
				(justify left bottom mirror)
			)
		)
		(fp_text user "Author: Antmicro"
			(at -1.682 -4.894 0)
			(layer "B.Fab")
			(effects
				(font
					(size 0.7 0.7)
					(thickness 0.15)
				)
				(justify left bottom mirror)
			)
		)
		(fp_text user "${REFERENCE}"
			(at -1.682 -3.895 0)
			(layer "B.Fab")
			(effects
				(font
					(size 0.7 0.7)
					(thickness 0.15)
				)
				(justify left bottom mirror)
			)
		)
		(pad "1" smd roundrect
			(at -0.7 0 180)
			(size 0.8 1.1)
			(layers "B.Cu" "B.Mask" "B.Paste")
			(roundrect_rratio 0.2)
			(net 1 "GND")
			(pintype "passive")
		)
		(pad "2" smd roundrect
			(at 0.7 0 180)
			(size 0.8 1.1)
			(layers "B.Cu" "B.Mask" "B.Paste")
			(roundrect_rratio 0.2)
			(net 213 "+5V_SOM")
			(pintype "passive")
		)
	)
)
